FILE_TYPE = CONNECTIVITY;
{Allegro Design Entry HDL 16.6-p007 (v16-6-112F) 10/10/2012}
"PAGE_NUMBER" = 192;
0"NC";
1"GND\g";
2"GND\g";
3"P3V3_STBY\g";
4"P3V3_STBY\g";
5"P3V3_STBY\g";
6"P3V3_STBY\g";
7"P3V3_STBY\g";
8"P3V3_STBY\g";
9"P3V3_STBY\g";
10"GND\g";
11"PVPP_ABC\g";
12"P3V3_STBY\g";
13"P3V3_STBY\g";
14"GND\g";
15"PVPP_KLM\g";
16"RST_CD_CPU0_POR_N";
17"RST_CD_CPU1_POR_N";
18"FM_MEM_EVENT_FUNC";
19"FM_PLD_DEBUG_MODE_N";
20"RST_RSMRST_N";
21"PU_THERMTRIP_FORCE_N";
22"PU_RST_PERST_BIT1";
23"PU_RST_PERST_BIT0";
24"NC_CPLD1";
%"CAP_A"
"1","(-1225,1975)","0","dev_discrete","I1";
;
CDS_LIB"dev_discrete"
$SEC"1"
CDS_SEC"1"
SIGNAL_MODEL"DEFAULT_CAPACITOR_10000pF_2_1"
BOM_COST"CPLD"
CDS_LOCATION"C2P8"
ROOM"CPLD"
MATERIAL"X7R"
VOLTAGE"25V"
PACK_TYPE"0402V"
TOLERANCE"10%"
VALUE"0.01UF"
PART_NUMBER"A36096-045"
LOCATION"C2P8";
"B"
$PN"2"1;
"A"
$PN"1"4;
%"CAP_A"
"1","(-4075,1975)","0","dev_discrete","I10";
;
CDS_LIB"dev_discrete"
CDS_LOCATION"C3R2"
$SEC"1"
CDS_SEC"1"
BOM_COST"CPLD"
SIGNAL_MODEL"DEFAULT_CAPACITOR_100000pF_2_1"
ROOM"CPLD"
MATERIAL"X7R"
VOLTAGE"16V"
PACK_TYPE"0402V"
TOLERANCE"10%"
VALUE"0.1UF"
PART_NUMBER"A36096-030"
LOCATION"C3R2";
"B"
$PN"2"1;
"A"
$PN"1"4;
%"CAP_A"
"1","(-3700,1300)","0","dev_discrete","I11";
;
CDS_LIB"dev_discrete"
CDS_LOCATION"C3P51"
SIGNAL_MODEL"DEFAULT_CAPACITOR_100000pF_2_1"
BOM_COST"CPLD"
CDS_SEC"1"
$SEC"1"
ROOM"CPLD"
MATERIAL"X7R"
VOLTAGE"16V"
PACK_TYPE"0402V"
TOLERANCE"10%"
VALUE"0.1UF"
PART_NUMBER"A36096-030"
LOCATION"C3P51";
"B"
$PN"2"2;
"A"
$PN"1"5;
%"CAP_A"
"1","(-4200,1300)","0","dev_discrete","I12";
;
CDS_LIB"dev_discrete"
CDS_LOCATION"C3P47"
SIGNAL_MODEL"DEFAULT_CAPACITOR_100000pF_2_1"
BOM_COST"CPLD"
CDS_SEC"1"
$SEC"1"
ROOM"CPLD"
MATERIAL"X7R"
VOLTAGE"16V"
PACK_TYPE"0402V"
TOLERANCE"10%"
VALUE"0.1UF"
PART_NUMBER"A36096-030"
LOCATION"C3P47";
"B"
$PN"2"2;
"A"
$PN"1"5;
%"LCMXO2_A"
"6","(-1850,3900)","0","mstr_memory","I14";
;
CDS_SEC"3"
CDS_LOCATION"U8D7"
BOM_COST"CPLD"
CDS_LMAN_SYM_OUTLINE"-400,750,400,-750"
CDS_LIB"mstr_memory"
SEC"3"
SEC_TYPE"256BGA"
ROOM"CPLD"
PACK_TYPE"256BGA"
MATERIAL"IC"
PART_NUMBER"H63395-001"
LOCATION"U8D7";
"VCC<3>"
$PN"T16"3;
"VCC<2>"
$PN"T1"3;
"VCC<1>"
$PN"A16"3;
"VCC<0>"
$PN"A1"3;
"GND<14>"
$PN"L6"10;
"GND<23>"
$PN"R15"10;
"NC<0>"
$PN"A2"24;
"GND<0>"
$PN"B2"10;
"GND<1>"
$PN"B15"10;
"GND<2>"
$PN"C3"10;
"GND<3>"
$PN"C14"10;
"GND<4>"
$PN"D4"10;
"GND<5>"
$PN"D13"10;
"GND<6>"
$PN"E5"10;
"GND<7>"
$PN"E12"10;
"GND<8>"
$PN"F6"10;
"GND<9>"
$PN"F11"10;
"GND<10>"
$PN"H8"10;
"GND<11>"
$PN"H9"10;
"GND<12>"
$PN"J8"10;
"GND<13>"
$PN"J9"10;
"GND<15>"
$PN"L11"10;
"GND<16>"
$PN"M5"10;
"GND<17>"
$PN"M12"10;
"GND<18>"
$PN"N4"10;
"GND<19>"
$PN"N13"10;
"GND<20>"
$PN"P3"10;
"GND<21>"
$PN"P14"10;
"GND<22>"
$PN"R2"10;
"VCC<4>"
$PN"G7"3;
"VCC<5>"
$PN"G10"3;
"VCC<6>"
$PN"K7"3;
"VCC<7>"
$PN"K10"3;
"VCCIO0<0>"
$PN"G8"3;
"VCCIO0<1>"
$PN"D12"3;
"VCCIO0<2>"
$PN"G9"3;
"VCCIO1<0>"
$PN"E13"3;
"VCCIO1<1>"
$PN"H10"3;
"VCCIO1<2>"
$PN"J10"3;
"VCCIO1<3>"
$PN"M13"3;
"VCCIO2<0>"
$PN"K9"3;
"VCCIO2<1>"
$PN"N12"3;
"VCCIO2<2>"
$PN"K8"3;
"VCCIO2<3>"
$PN"N5"3;
"VCCIO4<0>"
$PN"J7"3;
"VCCIO4<1>"
$PN"H7"3;
"VCCIO5<0>"
$PN"E4"3;
"VCCIO0<3>"
$PN"D5"3;
"VCCIO3<0>"
$PN"M4"3;
%"CAP_A"
"1","(-4550,1975)","0","dev_discrete","I15";
;
CDS_LIB"dev_discrete"
CDS_LOCATION"C2R5"
$SEC"1"
CDS_SEC"1"
BOM_COST"CPLD"
SIGNAL_MODEL"DEFAULT_CAPACITOR_100000pF_2_1"
ROOM"CPLD"
MATERIAL"X7R"
VOLTAGE"16V"
PACK_TYPE"0402V"
TOLERANCE"10%"
VALUE"0.1UF"
PART_NUMBER"A36096-030"
LOCATION"C2R5";
"B"
$PN"2"1;
"A"
$PN"1"4;
%"CAP_A"
"1","(-5025,1975)","0","dev_discrete","I16";
;
CDS_LIB"dev_discrete"
$SEC"1"
CDS_SEC"1"
BOM_COST"CPLD"
SIGNAL_MODEL"DEFAULT_CAPACITOR_100000pF_2_1"
CDS_LOCATION"C2P4"
ROOM"CPLD"
MATERIAL"X7R"
VOLTAGE"16V"
PACK_TYPE"0402V"
TOLERANCE"10%"
VALUE"0.1UF"
PART_NUMBER"A36096-030"
LOCATION"C2P4";
"B"
$PN"2"1;
"A"
$PN"1"4;
%"CAP_A"
"1","(-4725,1300)","0","dev_discrete","I17";
;
CDS_LIB"dev_discrete"
CDS_LOCATION"C3P52"
SIGNAL_MODEL"DEFAULT_CAPACITOR_100000pF_2_1"
BOM_COST"CPLD"
$SEC"1"
CDS_SEC"1"
ROOM"CPLD"
MATERIAL"X7R"
VOLTAGE"16V"
PACK_TYPE"0402V"
TOLERANCE"10%"
VALUE"0.1UF"
PART_NUMBER"A36096-030"
LOCATION"C3P52";
"B"
$PN"2"2;
"A"
$PN"1"5;
%"CAP_A"
"1","(-5225,1300)","0","dev_discrete","I18";
;
CDS_LIB"dev_discrete"
CDS_LOCATION"C2P6"
SIGNAL_MODEL"DEFAULT_CAPACITOR_100000pF_2_1"
BOM_COST"CPLD"
CDS_SEC"1"
$SEC"1"
ROOM"CPLD"
MATERIAL"X7R"
VOLTAGE"16V"
PACK_TYPE"0402V"
TOLERANCE"10%"
VALUE"0.1UF"
PART_NUMBER"A36096-030"
LOCATION"C2P6";
"B"
$PN"2"2;
"A"
$PN"1"5;
%"CAP_A"
"1","(-5500,1975)","0","dev_discrete","I19";
;
CDS_LIB"dev_discrete"
CDS_LOCATION"C2R3"
SIGNAL_MODEL"DEFAULT_CAPACITOR_100000pF_2_1"
BOM_COST"CPLD"
CDS_SEC"1"
$SEC"1"
ROOM"CPLD"
MATERIAL"X7R"
VOLTAGE"16V"
PACK_TYPE"0402V"
TOLERANCE"10%"
VALUE"0.1UF"
PART_NUMBER"A36096-030"
LOCATION"C2R3";
"B"
$PN"2"1;
"A"
$PN"1"4;
%"GND"
"1","(-1225,1625)","0","mstr_symbols","I2";
;
BOM_COST"CPLD"
BODY_TYPE"PLUMBING"
CDS_LIB"mstr_symbols"
SIZE"1B"
ROOM"CPLD"
HDL_POWER"GND"
VOLTAGE"0.0V";
"A\NAC"1;
%"CAP_A"
"1","(-5975,1975)","0","dev_discrete","I20";
;
CDS_LIB"dev_discrete"
CDS_LOCATION"C2P7"
BOM_COST"CPLD"
SIGNAL_MODEL"DEFAULT_CAPACITOR_100000pF_2_1"
CDS_SEC"1"
$SEC"1"
ROOM"CPLD"
MATERIAL"X7R"
VOLTAGE"16V"
PACK_TYPE"0402V"
TOLERANCE"10%"
VALUE"0.1UF"
PART_NUMBER"A36096-030"
LOCATION"C2P7";
"B"
$PN"2"1;
"A"
$PN"1"4;
%"CAP_A"
"1","(-5700,1300)","0","dev_discrete","I21";
;
CDS_LIB"dev_discrete"
CDS_LOCATION"C2R4"
SIGNAL_MODEL"DEFAULT_CAPACITOR_100000pF_2_1"
BOM_COST"CPLD"
$SEC"1"
CDS_SEC"1"
ROOM"CPLD"
MATERIAL"X7R"
VOLTAGE"16V"
PACK_TYPE"0402V"
TOLERANCE"10%"
VALUE"0.1UF"
PART_NUMBER"A36096-030"
LOCATION"C2R4";
"B"
$PN"2"2;
"A"
$PN"1"5;
%"CAP_A"
"1","(-6250,1300)","0","dev_discrete","I22";
;
CDS_LIB"dev_discrete"
CDS_LOCATION"C2P3"
SIGNAL_MODEL"DEFAULT_CAPACITOR_100000pF_2_1"
BOM_COST"CPLD"
CDS_SEC"1"
$SEC"1"
ROOM"CPLD"
MATERIAL"X7R"
VOLTAGE"16V"
PACK_TYPE"0402V"
TOLERANCE"10%"
VALUE"0.1UF"
PART_NUMBER"A36096-030"
LOCATION"C2P3";
"B"
$PN"2"2;
"A"
$PN"1"5;
%"CAP_A"
"1","(-6450,1975)","0","dev_discrete","I23";
;
CDS_LIB"dev_discrete"
$SEC"1"
CDS_SEC"1"
SIGNAL_MODEL"DEFAULT_CAPACITOR_100000pF_2_1"
BOM_COST"CPLD"
CDS_LOCATION"C3P44"
ROOM"CPLD"
MATERIAL"X7R"
VOLTAGE"16V"
PACK_TYPE"0402V"
TOLERANCE"10%"
VALUE"0.1UF"
PART_NUMBER"A36096-030"
LOCATION"C3P44";
"B"
$PN"2"1;
"A"
$PN"1"4;
%"CAP_A"
"1","(-6925,1975)","0","dev_discrete","I25";
;
CDS_LIB"dev_discrete"
CDS_LOCATION"C3P48"
SIGNAL_MODEL"DEFAULT_CAPACITOR_100000pF_2_1"
BOM_COST"CPLD"
CDS_SEC"1"
SEC_TYPE"0402V"
SEC"1"
ROOM"CPLD"
MATERIAL"X7R"
VOLTAGE"16V"
PACK_TYPE"0402V"
TOLERANCE"10%"
VALUE"0.1UF"
PART_NUMBER"A36096-030"
LOCATION"C3P48";
"B"
$PN"2"1;
"A"
$PN"1"4;
%"GND"
"1","(-6475,1000)","0","mstr_symbols","I26";
;
SIZE"1B"
BODY_TYPE"PLUMBING"
CDS_LIB"mstr_symbols"
BOM_COST"CPLD"
ROOM"CPLD"
HDL_POWER"GND"
VOLTAGE"0.0V";
"A\NAC"2;
%"CAP_A"
"1","(-6850,1300)","0","dev_discrete","I28";
;
CDS_LIB"dev_discrete"
CDS_LOCATION"C2R2"
SIGNAL_MODEL"DEFAULT_CAPACITOR_100000pF_2_1"
BOM_COST"CPLD"
CDS_SEC"1"
$SEC"1"
ROOM"CPLD"
MATERIAL"X7R"
VOLTAGE"16V"
PACK_TYPE"0402V"
TOLERANCE"10%"
VALUE"0.1UF"
PART_NUMBER"A36096-030"
LOCATION"C2R2";
"B"
$PN"2"2;
"A"
$PN"1"5;
%"P3V3_STBY"
"1","(-2500,4700)","0","mstr_symbols","I29";
;
BODY_TYPE"PLUMBING"
CDS_LIB"mstr_symbols"
SIZE"1B"
HDL_POWER"P3V3_STBY"
VOLTAGE"3.3V";
"G\NAC"3;
%"CAP_A"
"1","(-1700,1975)","0","dev_discrete","I3";
;
CDS_LIB"dev_discrete"
$SEC"1"
CDS_SEC"1"
BOM_COST"CPLD"
SIGNAL_MODEL"DEFAULT_CAPACITOR_100000pF_2_1"
CDS_LOCATION"C2P5"
ROOM"CPLD"
MATERIAL"X7R"
VOLTAGE"16V"
PACK_TYPE"0402V"
TOLERANCE"10%"
VALUE"0.1UF"
PART_NUMBER"A36096-030"
LOCATION"C2P5";
"B"
$PN"2"1;
"A"
$PN"1"4;
%"P3V3_STBY"
"1","(-6925,2275)","0","mstr_symbols","I30";
;
BODY_TYPE"PLUMBING"
CDS_LIB"mstr_symbols"
SIZE"1B"
HDL_POWER"P3V3_STBY"
VOLTAGE"3.3V";
"G\NAC"4;
%"P3V3_STBY"
"1","(-6850,1525)","0","mstr_symbols","I31";
;
BODY_TYPE"PLUMBING"
CDS_LIB"mstr_symbols"
SIZE"1B"
HDL_POWER"P3V3_STBY"
VOLTAGE"3.3V";
"G\NAC"5;
%"P3V3_STBY"
"1","(-6150,4600)","0","mstr_symbols","I32";
;
BODY_TYPE"PLUMBING"
CDS_LIB"mstr_symbols"
SIZE"1B"
HDL_POWER"P3V3_STBY"
VOLTAGE"3.3V";
"G\NAC"6;
%"RES"
"2","(-6150,4400)","0","mstr_discrete","I33";
;
CDS_LIB"mstr_discrete"
CDS_LOCATION"R7E6"
BOM_COST"CPLD"
CDS_SEC"1"
$SEC"1"
ROOM"CPLD"
WATTAGE"1/16W"
MATERIAL"CHIP"
PACK_TYPE"0402"
TOLERANCE"1%"
VALUE"10.0K"
PART_NUMBER"G21796-016"
LOCATION"R7E6";
"A"
$PN"1"6;
"B"
$PN"2"22;
%"RES"
"2","(-5750,4400)","0","mstr_discrete","I34";
;
CDS_LIB"mstr_discrete"
CDS_LOCATION"R2R1"
BOM_COST"CPLD"
CDS_SEC"1"
$SEC"1"
ROOM"CPLD"
WATTAGE"1/16W"
MATERIAL"CHIP"
PACK_TYPE"0402"
TOLERANCE"1%"
VALUE"10.0K"
PART_NUMBER"G21796-016"
LOCATION"R2R1";
"A"
$PN"1"7;
"B"
$PN"2"23;
%"P3V3_STBY"
"1","(-5750,4600)","0","mstr_symbols","I35";
;
BODY_TYPE"PLUMBING"
CDS_LIB"mstr_symbols"
SIZE"1B"
HDL_POWER"P3V3_STBY"
VOLTAGE"3.3V";
"G\NAC"7;
%"RES"
"2","(-6550,4400)","0","mstr_discrete","I38";
;
CDS_LIB"mstr_discrete"
CDS_LOCATION"R7E5"
BOM_COST"CPLD"
CDS_SEC"1"
$SEC"1"
ROOM"CPLD"
WATTAGE"1/16W"
MATERIAL"CHIP"
PACK_TYPE"0402"
TOLERANCE"1%"
VALUE"10.0K"
PART_NUMBER"G21796-016"
LOCATION"R7E5";
"A"
$PN"1"8;
"B"
$PN"2"21;
%"P3V3_STBY"
"1","(-6550,4600)","0","mstr_symbols","I39";
;
BODY_TYPE"PLUMBING"
CDS_LIB"mstr_symbols"
SIZE"1B"
HDL_POWER"P3V3_STBY"
VOLTAGE"3.3V";
"G\NAC"8;
%"CAP_A"
"1","(-2175,1975)","0","dev_discrete","I4";
;
CDS_LIB"dev_discrete"
CDS_LOCATION"C3R1"
SIGNAL_MODEL"DEFAULT_CAPACITOR_100000pF_2_1"
$SEC"1"
BOM_COST"CPLD"
CDS_SEC"1"
ROOM"CPLD"
MATERIAL"X7R"
VOLTAGE"16V"
PACK_TYPE"0402V"
TOLERANCE"10%"
VALUE"0.1UF"
PART_NUMBER"A36096-030"
LOCATION"C3R1";
"B"
$PN"2"1;
"A"
$PN"1"4;
%"RES"
"2","(-6950,4400)","0","mstr_discrete","I41";
;
CDS_LIB"mstr_discrete"
CDS_LOCATION"R2R3"
BOM_COST"CPLD"
CDS_SEC"1"
$SEC"1"
ROOM"CPLD"
WATTAGE"1/16W"
MATERIAL"CHIP"
PACK_TYPE"0402"
TOLERANCE"1%"
VALUE"10.0K"
PART_NUMBER"G21796-016"
LOCATION"R2R3";
"A"
$PN"1"9;
"B"
$PN"2"19;
%"P3V3_STBY"
"1","(-6950,4600)","0","mstr_symbols","I42";
;
BODY_TYPE"PLUMBING"
CDS_LIB"mstr_symbols"
SIZE"1B"
HDL_POWER"P3V3_STBY"
VOLTAGE"3.3V";
"G\NAC"9;
%"RES"
"2","(-6150,2800)","0","mstr_discrete","I48";
;
CDS_SEC"1"
CDS_LOCATION"R3R16"
CDS_LIB"mstr_discrete"
SEC_TYPE"0402"
SEC"1"
BOM_COST"CPLD"
ROOM"CPLD"
MATERIAL"CHIP"
WATTAGE"1/16W"
PACK_TYPE"0402"
TOLERANCE"1%"
VALUE"4.75K"
PART_NUMBER"G21796-072"
LOCATION"R3R16";
"A"
$PN"1"11;
"B"
$PN"2"16;
%"RES"
"2","(-5750,2800)","0","mstr_discrete","I49";
;
CDS_SEC"1"
CDS_LOCATION"R6M9"
CDS_LIB"mstr_discrete"
BOM_COST"CPLD"
SEC_TYPE"0402"
SEC"1"
ROOM"CPLD"
WATTAGE"1/16W"
MATERIAL"CHIP"
PACK_TYPE"0402"
TOLERANCE"1%"
VALUE"4.75K"
PART_NUMBER"G21796-072"
LOCATION"R6M9";
"A"
$PN"1"15;
"B"
$PN"2"17;
%"GND"
"1","(-1100,3100)","0","mstr_symbols","I5";
;
BODY_TYPE"PLUMBING"
SIZE"1B"
BOM_COST"CPLD"
CDS_LIB"mstr_symbols"
ROOM"CPLD"
HDL_POWER"GND"
VOLTAGE"0.0V";
"A\NAC"10;
%"PVPP_ABC"
"1","(-6150,3000)","0","mstr_symbols","I52";
;
BODY_TYPE"PLUMBING"
CDS_LIB"mstr_symbols"
BOM_COST"PVPP_KLM_VR"
ROOM"PVPP_KLM_VR"
HDL_POWER"PVPP_ABC"
VOLTAGE"2.5V";
"G\NAC"11;
%"RES"
"2","(-7350,4400)","0","mstr_discrete","I55";
;
CDS_LOCATION"R7E18"
CDS_LIB"mstr_discrete"
BOM_COST"CPLD"
CDS_SEC"1"
$SEC"1"
ROOM"CPLD"
WATTAGE"1/16W"
MATERIAL"CHIP"
PACK_TYPE"0402"
TOLERANCE"1%"
VALUE"4.75K"
PART_NUMBER"G21796-072"
LOCATION"R7E18";
"A"
$PN"1"12;
"B"
$PN"2"20;
%"P3V3_STBY"
"1","(-7350,4600)","0","mstr_symbols","I56";
;
BODY_TYPE"PLUMBING"
CDS_LIB"mstr_symbols"
SIZE"1B"
HDL_POWER"P3V3_STBY"
VOLTAGE"3.3V";
"G\NAC"12;
%"RES"
"2","(-7750,4400)","0","mstr_discrete","I57";
;
CDS_LOCATION"R7E19"
CDS_LIB"mstr_discrete"
BOM_COST"CPLD"
CDS_SEC"1"
$SEC"1"
ROOM"CPLD"
MATERIAL"EMPTY"
PART_NUMBER"G21796-026"
PACK_TYPE"0402"
WATTAGE"1/16W"
TOLERANCE"1%"
VALUE"1.00K"
LOCATION"R7E19";
"A"
$PN"1"13;
"B"
$PN"2"18;
%"P3V3_STBY"
"1","(-7750,4600)","0","mstr_symbols","I58";
;
BODY_TYPE"PLUMBING"
CDS_LIB"mstr_symbols"
SIZE"1B"
HDL_POWER"P3V3_STBY"
VOLTAGE"3.3V";
"G\NAC"13;
%"RES"
"2","(-7750,3500)","0","mstr_discrete","I59";
;
CDS_LOCATION"R7E20"
CDS_LIB"mstr_discrete"
BOM_COST"CPLD"
CDS_SEC"1"
$SEC"1"
ROOM"CPLD"
WATTAGE"1/16W"
MATERIAL"CHIP"
PACK_TYPE"0402"
TOLERANCE"1%"
VALUE"1.00K"
PART_NUMBER"G21796-026"
LOCATION"R7E20";
"A"
$PN"1"18;
"B"
$PN"2"14;
%"CAP_A"
"1","(-2650,1975)","0","dev_discrete","I6";
;
CDS_LIB"dev_discrete"
CDS_LOCATION"C3P43"
SIGNAL_MODEL"DEFAULT_CAPACITOR_100000pF_2_1"
BOM_COST"CPLD"
CDS_SEC"1"
$SEC"1"
ROOM"CPLD"
MATERIAL"X7R"
VOLTAGE"16V"
PACK_TYPE"0402V"
TOLERANCE"10%"
VALUE"0.1UF"
PART_NUMBER"A36096-030"
LOCATION"C3P43";
"B"
$PN"2"1;
"A"
$PN"1"4;
%"GND"
"1","(-7750,3300)","0","mstr_symbols","I61";
;
BODY_TYPE"PLUMBING"
CDS_LIB"mstr_symbols"
SIZE"1B"
HDL_POWER"GND"
VOLTAGE"0.0V";
"A\NAC"14;
%"PVPP_KLM"
"1","(-5750,3000)","0","mstr_symbols","I62";
;
BODY_TYPE"PLUMBING"
CDS_LIB"mstr_symbols"
BOM_COST"PVPP_KLM_VR"
ROOM"PVPP_KLM_VR"
HDL_POWER"PVPP_KLM"
VOLTAGE"2.5V";
"G\NAC"15;
%"CAP_A"
"1","(-3125,1975)","0","dev_discrete","I7";
;
CDS_LIB"dev_discrete"
CDS_LOCATION"C3R3"
$SEC"1"
CDS_SEC"1"
BOM_COST"CPLD"
SIGNAL_MODEL"DEFAULT_CAPACITOR_100000pF_2_1"
ROOM"CPLD"
MATERIAL"X7R"
VOLTAGE"16V"
PACK_TYPE"0402V"
TOLERANCE"10%"
VALUE"0.1UF"
PART_NUMBER"A36096-030"
LOCATION"C3R3";
"B"
$PN"2"1;
"A"
$PN"1"4;
%"CAP_A"
"1","(-3150,1300)","0","dev_discrete","I8";
;
CDS_LOCATION"C2R1"
CDS_LIB"dev_discrete"
SIGNAL_MODEL"DEFAULT_CAPACITOR_100000pF_2_1"
BOM_COST"CPLD"
CDS_SEC"1"
$SEC"1"
ROOM"CPLD"
MATERIAL"X7R"
VOLTAGE"16V"
PACK_TYPE"0402V"
TOLERANCE"10%"
VALUE"0.1UF"
PART_NUMBER"A36096-030"
LOCATION"C2R1";
"B"
$PN"2"2;
"A"
$PN"1"5;
%"CAP_A"
"1","(-3600,1975)","0","dev_discrete","I9";
;
CDS_LIB"dev_discrete"
CDS_LOCATION"C2P2"
SIGNAL_MODEL"DEFAULT_CAPACITOR_100000pF_2_1"
BOM_COST"CPLD"
CDS_SEC"1"
$SEC"1"
ROOM"CPLD"
MATERIAL"X7R"
VOLTAGE"16V"
PACK_TYPE"0402V"
TOLERANCE"10%"
VALUE"0.1UF"
PART_NUMBER"A36096-030"
LOCATION"C2P2";
"B"
$PN"2"1;
"A"
$PN"1"4;
END.
